G04*
G04 #@! TF.GenerationSoftware,Altium Limited,Altium Designer,23.6.0 (18)*
G04*
G04 Layer_Physical_Order=3*
G04 Layer_Color=6736896*
%FSLAX44Y44*%
%MOMM*%
G71*
G04*
G04 #@! TF.SameCoordinates,0D6CC9A4-690D-4EF8-AA6E-9FB67146BD04*
G04*
G04*
G04 #@! TF.FilePolarity,Positive*
G04*
G01*
G75*
%ADD76R,2.0200X2.0200*%
%ADD77C,2.0200*%
%ADD78C,2.0900*%
%ADD79C,5.3000*%
%ADD80C,0.6000*%
G36*
X503922Y502958D02*
X503922Y5000D01*
X503921Y4999D01*
X503290Y4368D01*
X502957Y4078D01*
X5000Y4078D01*
X4919D01*
X4078Y5042D01*
X4078Y502953D01*
X4746Y503699D01*
X5000Y503921D01*
X503000Y503922D01*
X503081D01*
X503922Y502958D01*
D02*
G37*
%LPC*%
G36*
X193522Y499450D02*
X190478D01*
X187493Y498856D01*
X184682Y497692D01*
X182151Y496001D01*
X179999Y493849D01*
X178308Y491318D01*
X177687Y489819D01*
X176313D01*
X175692Y491318D01*
X174001Y493849D01*
X171849Y496001D01*
X169318Y497692D01*
X166507Y498856D01*
X163522Y499450D01*
X160478D01*
X157493Y498856D01*
X154682Y497692D01*
X152151Y496001D01*
X149999Y493849D01*
X148308Y491318D01*
X147144Y488507D01*
X146550Y485522D01*
Y482478D01*
X147144Y479493D01*
X148308Y476682D01*
X149999Y474151D01*
X152151Y471999D01*
X154682Y470308D01*
X157493Y469144D01*
X160478Y468550D01*
X163522D01*
X166507Y469144D01*
X169318Y470308D01*
X171849Y471999D01*
X174001Y474151D01*
X175692Y476682D01*
X176313Y478181D01*
X177687D01*
X178308Y476682D01*
X179999Y474151D01*
X182151Y471999D01*
X184682Y470308D01*
X187493Y469144D01*
X190478Y468550D01*
X193522D01*
X196507Y469144D01*
X199318Y470308D01*
X201849Y471999D01*
X204001Y474151D01*
X205692Y476682D01*
X206856Y479493D01*
X207450Y482478D01*
Y485522D01*
X206856Y488507D01*
X205692Y491318D01*
X204001Y493849D01*
X201849Y496001D01*
X199318Y497692D01*
X196507Y498856D01*
X193522Y499450D01*
D02*
G37*
G36*
X242495Y483750D02*
X240505D01*
X238668Y482989D01*
X237261Y481582D01*
X236500Y479745D01*
Y477755D01*
X237261Y475918D01*
X238668Y474511D01*
X240505Y473750D01*
X242495D01*
X244332Y474511D01*
X245739Y475918D01*
X246500Y477755D01*
Y479745D01*
X245739Y481582D01*
X244332Y482989D01*
X242495Y483750D01*
D02*
G37*
G36*
X133639Y496450D02*
X130361D01*
X127194Y495602D01*
X124355Y493963D01*
X122037Y491645D01*
X120398Y488806D01*
X119550Y485639D01*
Y482361D01*
X120398Y479194D01*
X122037Y476356D01*
X124355Y474038D01*
X127194Y472398D01*
X130361Y471550D01*
X133639D01*
X136805Y472398D01*
X139644Y474038D01*
X141962Y476356D01*
X143602Y479194D01*
X144450Y482361D01*
Y485639D01*
X143602Y488806D01*
X141962Y491645D01*
X139644Y493963D01*
X136805Y495602D01*
X133639Y496450D01*
D02*
G37*
G36*
X103639D02*
X100361D01*
X97194Y495602D01*
X94355Y493963D01*
X92037Y491645D01*
X90398Y488806D01*
X89550Y485639D01*
Y482361D01*
X90398Y479194D01*
X92037Y476356D01*
X94355Y474038D01*
X97194Y472398D01*
X100361Y471550D01*
X103639D01*
X106805Y472398D01*
X109644Y474038D01*
X111962Y476356D01*
X113602Y479194D01*
X114450Y482361D01*
Y485639D01*
X113602Y488806D01*
X111962Y491645D01*
X109644Y493963D01*
X106805Y495602D01*
X103639Y496450D01*
D02*
G37*
G36*
X73639D02*
X70361D01*
X67194Y495602D01*
X64356Y493963D01*
X62038Y491645D01*
X60399Y488806D01*
X59550Y485639D01*
Y482361D01*
X60399Y479194D01*
X62038Y476356D01*
X64356Y474038D01*
X67194Y472398D01*
X70361Y471550D01*
X73639D01*
X76806Y472398D01*
X79644Y474038D01*
X81962Y476356D01*
X83602Y479194D01*
X84450Y482361D01*
Y485639D01*
X83602Y488806D01*
X81962Y491645D01*
X79644Y493963D01*
X76806Y495602D01*
X73639Y496450D01*
D02*
G37*
G36*
X49000Y469912D02*
X45986Y469105D01*
X43024Y467395D01*
X40605Y464976D01*
X38895Y462014D01*
X38088Y459000D01*
X49000D01*
Y469912D01*
D02*
G37*
G36*
X140744Y468508D02*
X138755D01*
X136918Y467747D01*
X135511Y466340D01*
X134750Y464503D01*
Y462514D01*
X135511Y460676D01*
X136918Y459269D01*
X138755Y458508D01*
X140744D01*
X142582Y459269D01*
X143989Y460676D01*
X144750Y462514D01*
Y464503D01*
X143989Y466340D01*
X142582Y467747D01*
X140744Y468508D01*
D02*
G37*
G36*
X53000Y469912D02*
Y459000D01*
X63912D01*
X63863Y459186D01*
X64017Y459366D01*
X65749Y459430D01*
X66168Y459011D01*
X68005Y458250D01*
X69995D01*
X71832Y459011D01*
X73239Y460418D01*
X74000Y462255D01*
Y464245D01*
X73239Y466082D01*
X71832Y467489D01*
X69995Y468250D01*
X68005D01*
X66168Y467489D01*
X64761Y466082D01*
X64000Y464245D01*
Y463003D01*
X62730Y462663D01*
X61395Y464976D01*
X58976Y467395D01*
X56014Y469105D01*
X53000Y469912D01*
D02*
G37*
G36*
X49000Y455000D02*
X38088D01*
X38895Y451986D01*
X40605Y449024D01*
X43024Y446605D01*
X45986Y444895D01*
X49000Y444088D01*
Y455000D01*
D02*
G37*
G36*
X63912D02*
X53000D01*
Y444088D01*
X56014Y444895D01*
X58976Y446605D01*
X61395Y449024D01*
X63105Y451986D01*
X63912Y455000D01*
D02*
G37*
G36*
X458522Y472450D02*
X455478D01*
X452493Y471856D01*
X449682Y470692D01*
X447151Y469001D01*
X444999Y466849D01*
X443308Y464318D01*
X442144Y461507D01*
X441550Y458522D01*
Y455478D01*
X442144Y452493D01*
X443308Y449682D01*
X444999Y447151D01*
X447151Y444999D01*
X449682Y443308D01*
X452493Y442144D01*
X455478Y441550D01*
X458522D01*
X461507Y442144D01*
X464318Y443308D01*
X466849Y444999D01*
X469001Y447151D01*
X470692Y449682D01*
X471856Y452493D01*
X472450Y455478D01*
Y458522D01*
X471856Y461507D01*
X470692Y464318D01*
X469001Y466849D01*
X466849Y469001D01*
X464318Y470692D01*
X461507Y471856D01*
X458522Y472450D01*
D02*
G37*
G36*
X415019Y472500D02*
X410981D01*
X407020Y471712D01*
X403290Y470167D01*
X399932Y467923D01*
X397077Y465068D01*
X394833Y461710D01*
X393288Y457980D01*
X392500Y454019D01*
Y449981D01*
X393288Y446020D01*
X394833Y442290D01*
X397077Y438932D01*
X399932Y436077D01*
X403290Y433833D01*
X407020Y432288D01*
X410981Y431500D01*
X415019D01*
X418980Y432288D01*
X422710Y433833D01*
X426068Y436077D01*
X428923Y438932D01*
X431167Y442290D01*
X432712Y446020D01*
X433500Y449981D01*
Y454019D01*
X432712Y457980D01*
X431167Y461710D01*
X428923Y465068D01*
X426068Y467923D01*
X422710Y470167D01*
X418980Y471712D01*
X415019Y472500D01*
D02*
G37*
G36*
X235392Y427690D02*
X233403D01*
X231566Y426929D01*
X230159Y425522D01*
X229398Y423685D01*
Y421696D01*
X230159Y419858D01*
X231566Y418451D01*
X233403Y417690D01*
X235392D01*
X237230Y418451D01*
X238637Y419858D01*
X239398Y421696D01*
Y423685D01*
X238637Y425522D01*
X237230Y426929D01*
X235392Y427690D01*
D02*
G37*
G36*
X97019Y457500D02*
X92981D01*
X89020Y456712D01*
X85289Y455167D01*
X81932Y452923D01*
X79077Y450068D01*
X76833Y446710D01*
X75288Y442980D01*
X74500Y439019D01*
Y434981D01*
X75288Y431020D01*
X76833Y427290D01*
X79077Y423932D01*
X81932Y421077D01*
X85289Y418833D01*
X89020Y417288D01*
X92981Y416500D01*
X97019D01*
X100980Y417288D01*
X104710Y418833D01*
X108068Y421077D01*
X110923Y423932D01*
X113167Y427290D01*
X114712Y431020D01*
X115500Y434981D01*
Y439019D01*
X114712Y442980D01*
X113167Y446710D01*
X110923Y450068D01*
X108068Y452923D01*
X104710Y455167D01*
X100980Y456712D01*
X97019Y457500D01*
D02*
G37*
G36*
X224367Y420288D02*
X222378D01*
X220540Y419527D01*
X219134Y418120D01*
X218373Y416283D01*
Y414294D01*
X219134Y412456D01*
X220540Y411049D01*
X222378Y410288D01*
X224367D01*
X226205Y411049D01*
X227611Y412456D01*
X228373Y414294D01*
Y416283D01*
X227611Y418120D01*
X226205Y419527D01*
X224367Y420288D01*
D02*
G37*
G36*
X18780Y402960D02*
X16791D01*
X14953Y402199D01*
X13547Y400792D01*
X12785Y398955D01*
Y396965D01*
X13547Y395128D01*
X14953Y393721D01*
X16791Y392960D01*
X18780D01*
X20618Y393721D01*
X22024Y395128D01*
X22785Y396965D01*
Y398955D01*
X22024Y400792D01*
X20618Y402199D01*
X18780Y402960D01*
D02*
G37*
G36*
X346264Y398919D02*
X344275D01*
X342437Y398158D01*
X341031Y396751D01*
X340269Y394914D01*
Y392924D01*
X341031Y391087D01*
X342437Y389680D01*
X344275Y388919D01*
X346264D01*
X348102Y389680D01*
X349508Y391087D01*
X350269Y392924D01*
Y394914D01*
X349508Y396751D01*
X348102Y398158D01*
X346264Y398919D01*
D02*
G37*
G36*
X316245Y397363D02*
X314256D01*
X312418Y396602D01*
X311011Y395196D01*
X310250Y393358D01*
Y391369D01*
X311011Y389531D01*
X312418Y388124D01*
X314256Y387363D01*
X316245D01*
X318082Y388124D01*
X319489Y389531D01*
X320250Y391369D01*
Y393358D01*
X319489Y395196D01*
X318082Y396602D01*
X316245Y397363D01*
D02*
G37*
G36*
X392022Y366264D02*
X390033D01*
X388195Y365503D01*
X386789Y364096D01*
X386028Y362258D01*
Y360269D01*
X386789Y358432D01*
X388195Y357025D01*
X390033Y356264D01*
X392022D01*
X393860Y357025D01*
X395266Y358432D01*
X396028Y360269D01*
Y362258D01*
X395266Y364096D01*
X393860Y365503D01*
X392022Y366264D01*
D02*
G37*
G36*
X18495Y372710D02*
X16505D01*
X14668Y371949D01*
X13261Y370542D01*
X12500Y368704D01*
Y366715D01*
X13261Y364878D01*
X14668Y363471D01*
X15148Y363272D01*
Y361898D01*
X14668Y361699D01*
X13261Y360292D01*
X12500Y358455D01*
Y356465D01*
X13261Y354628D01*
X14668Y353221D01*
X16505Y352460D01*
X18495D01*
X20332Y353221D01*
X21739Y354628D01*
X22500Y356465D01*
Y358455D01*
X21739Y360292D01*
X20332Y361699D01*
X19852Y361898D01*
Y363272D01*
X20332Y363471D01*
X21739Y364878D01*
X22500Y366715D01*
Y368704D01*
X21739Y370542D01*
X20332Y371949D01*
X18495Y372710D01*
D02*
G37*
G36*
X96604Y358378D02*
X94615D01*
X92777Y357617D01*
X91371Y356210D01*
X90610Y354372D01*
Y352383D01*
X91371Y350546D01*
X92777Y349139D01*
X94615Y348378D01*
X96604D01*
X98442Y349139D01*
X99848Y350546D01*
X100610Y352383D01*
Y354372D01*
X99848Y356210D01*
X98442Y357617D01*
X96604Y358378D01*
D02*
G37*
G36*
X355745Y344500D02*
X353755D01*
X351918Y343739D01*
X350511Y342332D01*
X349750Y340495D01*
Y338505D01*
X350511Y336668D01*
X351918Y335261D01*
X353755Y334500D01*
X355745D01*
X357582Y335261D01*
X358989Y336668D01*
X359750Y338505D01*
Y340495D01*
X358989Y342332D01*
X357582Y343739D01*
X355745Y344500D01*
D02*
G37*
G36*
X221963Y344000D02*
X219974D01*
X218136Y343239D01*
X216730Y341832D01*
X215968Y339995D01*
Y338005D01*
X216730Y336168D01*
X218136Y334761D01*
X219974Y334000D01*
X221963D01*
X223801Y334761D01*
X225207Y336168D01*
X225968Y338005D01*
Y339995D01*
X225207Y341832D01*
X223801Y343239D01*
X221963Y344000D01*
D02*
G37*
G36*
X467243Y377500D02*
X462757D01*
X458326Y376798D01*
X454060Y375412D01*
X450063Y373375D01*
X446433Y370739D01*
X443261Y367566D01*
X440625Y363937D01*
X438588Y359940D01*
X437202Y355674D01*
X436500Y351243D01*
Y346757D01*
X437202Y342326D01*
X438588Y338060D01*
X440625Y334063D01*
X443261Y330434D01*
X446433Y327261D01*
X450063Y324625D01*
X454060Y322588D01*
X458326Y321202D01*
X462757Y320500D01*
X467243D01*
X471674Y321202D01*
X475940Y322588D01*
X479937Y324625D01*
X483567Y327261D01*
X486739Y330434D01*
X489375Y334063D01*
X491412Y338060D01*
X492798Y342326D01*
X493500Y346757D01*
Y351243D01*
X492798Y355674D01*
X491412Y359940D01*
X489375Y363937D01*
X486739Y367566D01*
X483567Y370739D01*
X479937Y373375D01*
X475940Y375412D01*
X471674Y376798D01*
X467243Y377500D01*
D02*
G37*
G36*
X245239Y297311D02*
X243250D01*
X241412Y296550D01*
X240006Y295143D01*
X239245Y293305D01*
Y291316D01*
X240006Y289479D01*
X241412Y288072D01*
X243250Y287311D01*
X245239D01*
X247077Y288072D01*
X248483Y289479D01*
X249245Y291316D01*
Y293305D01*
X248483Y295143D01*
X247077Y296550D01*
X245239Y297311D01*
D02*
G37*
G36*
X404053Y282430D02*
X401947D01*
X399912Y281885D01*
X398088Y280832D01*
X396599Y279343D01*
X395545Y277518D01*
X395000Y275484D01*
Y273377D01*
X395545Y271343D01*
X396599Y269518D01*
X398088Y268029D01*
X399912Y266976D01*
X401947Y266430D01*
X404053D01*
X406088Y266976D01*
X407912Y268029D01*
X409402Y269518D01*
X410455Y271343D01*
X411000Y273377D01*
Y275484D01*
X410455Y277518D01*
X409402Y279343D01*
X407912Y280832D01*
X406088Y281885D01*
X404053Y282430D01*
D02*
G37*
G36*
X459000Y266912D02*
Y256000D01*
X469912D01*
X469105Y259014D01*
X467395Y261976D01*
X464976Y264395D01*
X462014Y266105D01*
X459000Y266912D01*
D02*
G37*
G36*
X455000Y266912D02*
X451986Y266105D01*
X449024Y264395D01*
X446605Y261976D01*
X444895Y259014D01*
X444088Y256000D01*
X455000D01*
Y266912D01*
D02*
G37*
G36*
X244495Y262561D02*
X242505D01*
X240668Y261800D01*
X239261Y260393D01*
X238500Y258556D01*
Y256566D01*
X239261Y254729D01*
X240668Y253322D01*
X242505Y252561D01*
X244495D01*
X246332Y253322D01*
X247739Y254729D01*
X248500Y256566D01*
Y258556D01*
X247739Y260393D01*
X246332Y261800D01*
X244495Y262561D01*
D02*
G37*
G36*
X469912Y252000D02*
X459000D01*
Y241088D01*
X462014Y241895D01*
X464976Y243605D01*
X467395Y246024D01*
X469105Y248986D01*
X469912Y252000D01*
D02*
G37*
G36*
X455000D02*
X444088D01*
X444895Y248986D01*
X446605Y246024D01*
X449024Y243605D01*
X451986Y241895D01*
X455000Y241088D01*
Y252000D01*
D02*
G37*
G36*
X256317Y223728D02*
X71113Y223728D01*
X70333Y223573D01*
X69672Y223131D01*
X69229Y222469D01*
X69169Y222323D01*
X68049Y221203D01*
X67886Y220959D01*
X67698Y220733D01*
X67667Y220630D01*
X67607Y220542D01*
X67550Y220253D01*
X67463Y219972D01*
X67473Y219866D01*
X67452Y219761D01*
X67509Y219473D01*
X67537Y219180D01*
X68109Y217253D01*
X68159Y217158D01*
X68180Y217053D01*
X68580Y216089D01*
Y214911D01*
X68129Y213823D01*
X67296Y212990D01*
X66208Y212539D01*
X65030D01*
X63942Y212990D01*
X63109Y213823D01*
X62658Y214911D01*
Y216089D01*
X63109Y217177D01*
X63492Y217561D01*
X63619Y217751D01*
X63776Y217917D01*
X63838Y218078D01*
X63934Y218223D01*
X63979Y218447D01*
X64061Y218660D01*
X64232Y219665D01*
X64230Y219743D01*
X64252Y219817D01*
X64219Y220138D01*
X64211Y220460D01*
X64179Y220531D01*
X64171Y220608D01*
X64018Y220892D01*
X63886Y221187D01*
X63830Y221240D01*
X63793Y221308D01*
X62401Y222989D01*
X62326Y223050D01*
X62272Y223131D01*
X62020Y223300D01*
X61784Y223491D01*
X61691Y223519D01*
X61611Y223573D01*
X61313Y223632D01*
X61021Y223719D01*
X60925Y223709D01*
X60830Y223728D01*
X20311Y223728D01*
X20239Y223714D01*
X20167Y223723D01*
X19852Y223636D01*
X19530Y223573D01*
X19470Y223532D01*
X19400Y223513D01*
X19141Y223312D01*
X18869Y223130D01*
X18828Y223070D01*
X18771Y223026D01*
X14746Y218390D01*
X14583Y218105D01*
X14401Y217833D01*
X14387Y217762D01*
X14351Y217699D01*
X14310Y217374D01*
X14246Y217053D01*
Y28442D01*
X14246Y28442D01*
X14401Y27662D01*
X14843Y27000D01*
X14843Y27000D01*
X26219Y15624D01*
X26881Y15182D01*
X27661Y15027D01*
X243963D01*
X244744Y15182D01*
X245405Y15624D01*
X257759Y27978D01*
X258201Y28640D01*
X258356Y29420D01*
Y57932D01*
X258356Y177705D01*
X259933D01*
X261771Y178466D01*
X263178Y179873D01*
X263939Y181710D01*
Y183700D01*
X263178Y185537D01*
X261771Y186944D01*
X259933Y187705D01*
X258356D01*
Y204744D01*
X259933D01*
X261771Y205505D01*
X263178Y206912D01*
X263939Y208749D01*
Y210738D01*
X263178Y212576D01*
X261771Y213983D01*
X259933Y214744D01*
X258356D01*
Y221689D01*
X258201Y222469D01*
X257759Y223131D01*
X257097Y223573D01*
X256317Y223728D01*
D02*
G37*
G36*
X315995Y208311D02*
X314006D01*
X312168Y207550D01*
X310761Y206143D01*
X310000Y204306D01*
Y202316D01*
X310761Y200479D01*
X312168Y199072D01*
X314006Y198311D01*
X315995D01*
X317832Y199072D01*
X319239Y200479D01*
X320000Y202316D01*
Y204306D01*
X319239Y206143D01*
X317832Y207550D01*
X315995Y208311D01*
D02*
G37*
G36*
X280201Y195705D02*
X278212D01*
X276374Y194944D01*
X274967Y193537D01*
X274206Y191700D01*
Y189711D01*
X274967Y187873D01*
X276374Y186466D01*
X278212Y185705D01*
X280201D01*
X282038Y186466D01*
X283445Y187873D01*
X284206Y189711D01*
Y191700D01*
X283445Y193537D01*
X282038Y194944D01*
X280201Y195705D01*
D02*
G37*
G36*
X404053Y193091D02*
X401947D01*
X399912Y192545D01*
X398088Y191492D01*
X396599Y190003D01*
X395545Y188179D01*
X395000Y186144D01*
Y184037D01*
X395545Y182003D01*
X396599Y180179D01*
X398088Y178689D01*
X399912Y177636D01*
X401947Y177091D01*
X404053D01*
X406088Y177636D01*
X407912Y178689D01*
X409402Y180179D01*
X410455Y182003D01*
X411000Y184037D01*
Y186144D01*
X410455Y188179D01*
X409402Y190003D01*
X407912Y191492D01*
X406088Y192545D01*
X404053Y193091D01*
D02*
G37*
G36*
X352156Y131070D02*
X350167D01*
X348329Y130309D01*
X347171Y129150D01*
X346082Y130239D01*
X344245Y131000D01*
X342255D01*
X340418Y130239D01*
X339011Y128832D01*
X338250Y126995D01*
Y125005D01*
X339011Y123168D01*
X340418Y121761D01*
X340648Y121666D01*
Y120291D01*
X339918Y119989D01*
X338511Y118582D01*
X337750Y116745D01*
Y114755D01*
X338511Y112918D01*
X339918Y111511D01*
X340804Y111144D01*
Y109769D01*
X339738Y109328D01*
X338331Y107921D01*
X337570Y106083D01*
Y104094D01*
X338331Y102256D01*
X339738Y100850D01*
X339968Y100755D01*
Y99380D01*
X339238Y99078D01*
X337831Y97671D01*
X337070Y95833D01*
Y93844D01*
X337831Y92007D01*
X339238Y90600D01*
X340717Y89987D01*
X340844Y88669D01*
X340843Y88665D01*
X340418Y88489D01*
X339011Y87082D01*
X338250Y85245D01*
Y83255D01*
X339011Y81418D01*
X340418Y80011D01*
X340648Y79916D01*
Y78541D01*
X339918Y78239D01*
X338511Y76832D01*
X337750Y74995D01*
Y73005D01*
X338511Y71168D01*
X339918Y69761D01*
X340804Y69394D01*
Y68019D01*
X339738Y67578D01*
X338331Y66171D01*
X337570Y64333D01*
Y62344D01*
X338331Y60507D01*
X339738Y59100D01*
X339968Y59005D01*
Y57630D01*
X339238Y57328D01*
X337831Y55921D01*
X337070Y54083D01*
Y52094D01*
X337831Y50257D01*
X339238Y48850D01*
X339044Y47555D01*
X338750Y46845D01*
Y44856D01*
X339511Y43018D01*
X340918Y41611D01*
X341148Y41516D01*
Y40142D01*
X340418Y39839D01*
X339011Y38433D01*
X338250Y36595D01*
Y34606D01*
X339011Y32768D01*
X340418Y31361D01*
X342255Y30600D01*
X344245D01*
X346082Y31361D01*
X347489Y32768D01*
X348247Y34598D01*
X348917Y34320D01*
X350906D01*
X352743Y35081D01*
X354150Y36488D01*
X354245Y36718D01*
X355620D01*
X355922Y35988D01*
X357329Y34581D01*
X359167Y33820D01*
X361156D01*
X362994Y34581D01*
X364400Y35988D01*
X365161Y37826D01*
Y39815D01*
X364400Y41652D01*
X362994Y43059D01*
X361156Y43820D01*
X359167D01*
X357329Y43059D01*
X355922Y41652D01*
X355827Y41422D01*
X354452D01*
X354150Y42152D01*
X352743Y43559D01*
X350906Y44320D01*
X349903D01*
X348847Y44811D01*
X348750Y45493D01*
Y45897D01*
X349111Y46914D01*
X349923Y47070D01*
X351156D01*
X352994Y47831D01*
X354400Y49238D01*
X354495Y49468D01*
X355870D01*
X356172Y48738D01*
X357579Y47331D01*
X359417Y46570D01*
X361406D01*
X363243Y47331D01*
X364650Y48738D01*
X365411Y50575D01*
Y52565D01*
X364650Y54402D01*
X363243Y55809D01*
X361406Y56570D01*
X359417D01*
X357579Y55809D01*
X356172Y54402D01*
X356077Y54172D01*
X354702D01*
X354400Y54902D01*
X352994Y56309D01*
X351156Y57070D01*
X349167D01*
X347329Y56309D01*
X346836Y55816D01*
X346309Y55921D01*
X344902Y57328D01*
X344672Y57423D01*
Y58798D01*
X345402Y59100D01*
X346676Y60374D01*
X347775Y59275D01*
X349612Y58513D01*
X351601D01*
X353439Y59275D01*
X354846Y60681D01*
X354941Y60911D01*
X356316D01*
X356618Y60181D01*
X358025Y58775D01*
X359862Y58014D01*
X361851D01*
X363689Y58775D01*
X365096Y60181D01*
X365857Y62019D01*
Y64008D01*
X365096Y65846D01*
X363689Y67252D01*
X361851Y68014D01*
X359862D01*
X358025Y67252D01*
X356618Y65846D01*
X356523Y65616D01*
X355148D01*
X354846Y66346D01*
X353439Y67752D01*
X351601Y68513D01*
X349612D01*
X347775Y67752D01*
X346501Y66479D01*
X345402Y67578D01*
X344516Y67945D01*
Y69320D01*
X345582Y69761D01*
X346096Y70275D01*
X347329Y70831D01*
X348024Y70543D01*
X349167Y70070D01*
X351156D01*
X352994Y70831D01*
X354400Y72238D01*
X354495Y72468D01*
X355870D01*
X356172Y71738D01*
X357579Y70331D01*
X359417Y69570D01*
X361406D01*
X363243Y70331D01*
X364650Y71738D01*
X365411Y73576D01*
Y75565D01*
X364650Y77402D01*
X363243Y78809D01*
X361406Y79570D01*
X359417D01*
X357579Y78809D01*
X356172Y77402D01*
X356077Y77172D01*
X354702D01*
X354400Y77902D01*
X352994Y79309D01*
X351156Y80070D01*
X349167D01*
X347329Y79309D01*
X346816Y78796D01*
X346500Y78653D01*
X346311Y78731D01*
X346198Y79363D01*
X346216Y80145D01*
X347489Y81418D01*
X348250Y83255D01*
Y84636D01*
X349372Y85512D01*
X349423Y85524D01*
X349917Y85320D01*
X351906D01*
X353744Y86081D01*
X355150Y87488D01*
X355245Y87718D01*
X356620D01*
X356922Y86988D01*
X358329Y85581D01*
X360167Y84820D01*
X362156D01*
X363993Y85581D01*
X365400Y86988D01*
X366161Y88826D01*
Y90815D01*
X365400Y92652D01*
X363993Y94059D01*
X362156Y94820D01*
X360167D01*
X358329Y94059D01*
X356922Y92652D01*
X356827Y92422D01*
X355452D01*
X355150Y93152D01*
X353744Y94559D01*
X351906Y95320D01*
X349917D01*
X348340Y94667D01*
X347457Y95044D01*
X347070Y95346D01*
Y95833D01*
X346309Y97671D01*
X344950Y99030D01*
X344937Y99986D01*
X344951Y100346D01*
X345562Y100723D01*
X346876Y100350D01*
X346922Y100238D01*
X348329Y98831D01*
X350167Y98070D01*
X352156D01*
X353993Y98831D01*
X355400Y100238D01*
X355495Y100468D01*
X356870D01*
X357172Y99738D01*
X358579Y98331D01*
X360417Y97570D01*
X362406D01*
X364244Y98331D01*
X365650Y99738D01*
X366411Y101575D01*
Y103565D01*
X365650Y105402D01*
X364244Y106809D01*
X362406Y107570D01*
X360417D01*
X358579Y106809D01*
X357172Y105402D01*
X357077Y105172D01*
X355702D01*
X355400Y105902D01*
X353993Y107309D01*
X352156Y108070D01*
X350167D01*
X348421Y107347D01*
X348025Y107265D01*
X346996Y107469D01*
X346809Y107921D01*
X345402Y109328D01*
X344516Y109695D01*
Y111069D01*
X345582Y111511D01*
X346087Y112015D01*
X347332Y111768D01*
X347368Y111681D01*
X348775Y110275D01*
X350612Y109514D01*
X352601D01*
X354439Y110275D01*
X355846Y111681D01*
X355941Y111911D01*
X357316D01*
X357618Y111181D01*
X359025Y109775D01*
X360862Y109014D01*
X362851D01*
X364689Y109775D01*
X366096Y111181D01*
X366857Y113019D01*
Y115008D01*
X366096Y116846D01*
X364689Y118252D01*
X362851Y119014D01*
X360862D01*
X359025Y118252D01*
X357618Y116846D01*
X357523Y116616D01*
X356148D01*
X355846Y117346D01*
X354439Y118752D01*
X352601Y119514D01*
X350612D01*
X348775Y118752D01*
X348270Y118248D01*
X347025Y118496D01*
X346989Y118582D01*
X345582Y119989D01*
X345352Y120084D01*
Y121459D01*
X346082Y121761D01*
X347241Y122920D01*
X348329Y121831D01*
X350167Y121070D01*
X352156D01*
X353993Y121831D01*
X355400Y123238D01*
X355495Y123468D01*
X356870D01*
X357172Y122738D01*
X358579Y121331D01*
X360417Y120570D01*
X362406D01*
X364244Y121331D01*
X365650Y122738D01*
X366411Y124576D01*
Y126565D01*
X365650Y128402D01*
X364244Y129809D01*
X362406Y130570D01*
X360417D01*
X358579Y129809D01*
X357172Y128402D01*
X357077Y128172D01*
X355702D01*
X355400Y128902D01*
X353993Y130309D01*
X352156Y131070D01*
D02*
G37*
G36*
X467243Y166500D02*
X462757D01*
X458326Y165798D01*
X454060Y164412D01*
X450063Y162375D01*
X446433Y159739D01*
X443261Y156566D01*
X440625Y152937D01*
X438588Y148940D01*
X437202Y144674D01*
X436500Y140243D01*
Y135757D01*
X437202Y131326D01*
X438588Y127060D01*
X440625Y123063D01*
X443261Y119433D01*
X446433Y116261D01*
X450063Y113625D01*
X454060Y111588D01*
X458326Y110202D01*
X462757Y109500D01*
X467243D01*
X471674Y110202D01*
X475940Y111588D01*
X479937Y113625D01*
X483567Y116261D01*
X486739Y119433D01*
X489375Y123063D01*
X491412Y127060D01*
X492798Y131326D01*
X493500Y135757D01*
Y140243D01*
X492798Y144674D01*
X491412Y148940D01*
X489375Y152937D01*
X486739Y156566D01*
X483567Y159739D01*
X479937Y162375D01*
X475940Y164412D01*
X471674Y165798D01*
X467243Y166500D01*
D02*
G37*
G36*
X458639Y63450D02*
X455361D01*
X452195Y62602D01*
X449356Y60963D01*
X447038Y58644D01*
X445398Y55806D01*
X444550Y52639D01*
Y49361D01*
X445398Y46195D01*
X447038Y43355D01*
X449356Y41038D01*
X452195Y39398D01*
X455361Y38550D01*
X458639D01*
X461805Y39398D01*
X464645Y41038D01*
X466963Y43355D01*
X468602Y46195D01*
X469450Y49361D01*
Y52639D01*
X468602Y55806D01*
X466963Y58644D01*
X464645Y60963D01*
X461805Y62602D01*
X458639Y63450D01*
D02*
G37*
G36*
X308495Y131250D02*
X306505D01*
X304668Y130489D01*
X303261Y129082D01*
X302500Y127245D01*
Y125255D01*
X303261Y123418D01*
X304668Y122011D01*
X304898Y121916D01*
Y120541D01*
X304168Y120239D01*
X302761Y118832D01*
X302000Y116995D01*
Y115005D01*
X302761Y113168D01*
X304168Y111761D01*
X305054Y111394D01*
Y110019D01*
X303988Y109578D01*
X302581Y108171D01*
X301820Y106333D01*
Y104344D01*
X302581Y102507D01*
X303988Y101100D01*
X304218Y101005D01*
Y99630D01*
X303488Y99328D01*
X302081Y97921D01*
X301320Y96083D01*
Y94094D01*
X302081Y92256D01*
X303488Y90850D01*
X304967Y90237D01*
X305094Y88919D01*
X305093Y88915D01*
X304668Y88739D01*
X303261Y87332D01*
X302500Y85494D01*
Y83505D01*
X303261Y81668D01*
X304668Y80261D01*
X304898Y80166D01*
Y78791D01*
X304168Y78489D01*
X302761Y77082D01*
X302000Y75245D01*
Y73255D01*
X302761Y71418D01*
X304168Y70011D01*
X305054Y69644D01*
Y68269D01*
X303988Y67828D01*
X302581Y66421D01*
X301820Y64583D01*
Y62594D01*
X302581Y60757D01*
X303988Y59350D01*
X304218Y59255D01*
Y57880D01*
X303488Y57578D01*
X302081Y56171D01*
X301320Y54333D01*
Y52344D01*
X302081Y50507D01*
X303488Y49100D01*
X303294Y47806D01*
X303000Y47095D01*
Y45106D01*
X303761Y43268D01*
X305168Y41862D01*
X305398Y41766D01*
Y40392D01*
X304668Y40089D01*
X303261Y38682D01*
X302500Y36845D01*
Y34856D01*
X303261Y33018D01*
X304668Y31611D01*
X306505Y30850D01*
X308495D01*
X310332Y31611D01*
X311739Y33018D01*
X312500Y34856D01*
Y36845D01*
X311739Y38682D01*
X310332Y40089D01*
X310102Y40184D01*
Y41559D01*
X310832Y41862D01*
X312239Y43268D01*
X313000Y45106D01*
Y47095D01*
X312239Y48932D01*
X310832Y50339D01*
X310571Y50447D01*
X310559Y50507D01*
X311320Y52344D01*
Y54333D01*
X310559Y56171D01*
X309152Y57578D01*
X308922Y57673D01*
Y59048D01*
X309652Y59350D01*
X311059Y60757D01*
X311820Y62594D01*
Y64583D01*
X311059Y66421D01*
X309652Y67828D01*
X308766Y68195D01*
Y69570D01*
X309832Y70011D01*
X311239Y71418D01*
X312000Y73255D01*
Y75245D01*
X311239Y77082D01*
X309832Y78489D01*
X309602Y78584D01*
Y79959D01*
X310332Y80261D01*
X311739Y81668D01*
X312500Y83505D01*
Y85494D01*
X311739Y87332D01*
X310332Y88739D01*
X308853Y89351D01*
X308726Y90670D01*
X308727Y90674D01*
X309152Y90850D01*
X310559Y92256D01*
X311320Y94094D01*
Y96083D01*
X310559Y97921D01*
X309152Y99328D01*
X308922Y99423D01*
Y100798D01*
X309652Y101100D01*
X311059Y102507D01*
X311820Y104344D01*
Y106333D01*
X311059Y108171D01*
X309652Y109578D01*
X308766Y109945D01*
Y111320D01*
X309832Y111761D01*
X311239Y113168D01*
X312000Y115005D01*
Y116995D01*
X311239Y118832D01*
X309832Y120239D01*
X309602Y120334D01*
Y121709D01*
X310332Y122011D01*
X311739Y123418D01*
X312500Y125255D01*
Y127245D01*
X311739Y129082D01*
X310332Y130489D01*
X308495Y131250D01*
D02*
G37*
G36*
X321245Y131000D02*
X319255D01*
X317418Y130239D01*
X316011Y128832D01*
X315250Y126995D01*
Y125005D01*
X316011Y123168D01*
X317418Y121761D01*
X317648Y121666D01*
Y120291D01*
X316918Y119989D01*
X315511Y118582D01*
X314750Y116745D01*
Y114755D01*
X315511Y112918D01*
X316918Y111511D01*
X317804Y111144D01*
Y109769D01*
X316738Y109328D01*
X315331Y107921D01*
X314570Y106083D01*
Y104094D01*
X315331Y102256D01*
X316738Y100850D01*
X316968Y100755D01*
Y99380D01*
X316238Y99078D01*
X314831Y97671D01*
X314070Y95833D01*
Y93844D01*
X314831Y92007D01*
X316238Y90600D01*
X317717Y89987D01*
X317844Y88669D01*
X317843Y88665D01*
X317418Y88489D01*
X316011Y87082D01*
X315250Y85245D01*
Y83255D01*
X316011Y81418D01*
X317418Y80011D01*
X317648Y79916D01*
Y78541D01*
X316918Y78239D01*
X315511Y76832D01*
X314750Y74995D01*
Y73005D01*
X315511Y71168D01*
X316918Y69761D01*
X317804Y69394D01*
Y68019D01*
X316738Y67578D01*
X315331Y66171D01*
X314570Y64333D01*
Y62344D01*
X315331Y60507D01*
X316738Y59100D01*
X316968Y59005D01*
Y57630D01*
X316238Y57328D01*
X314831Y55921D01*
X314070Y54083D01*
Y52094D01*
X314831Y50257D01*
X316238Y48850D01*
X316044Y47555D01*
X315750Y46845D01*
Y44856D01*
X316511Y43018D01*
X317918Y41611D01*
X318148Y41516D01*
Y40142D01*
X317418Y39839D01*
X316011Y38433D01*
X315250Y36595D01*
Y34606D01*
X316011Y32768D01*
X317418Y31361D01*
X319255Y30600D01*
X321245D01*
X323082Y31361D01*
X324489Y32768D01*
X325250Y34606D01*
Y36595D01*
X324489Y38433D01*
X323082Y39839D01*
X322852Y39934D01*
Y41309D01*
X323582Y41611D01*
X324989Y43018D01*
X325750Y44856D01*
Y46845D01*
X324989Y48683D01*
X323582Y50089D01*
X323776Y51384D01*
X324070Y52094D01*
Y54083D01*
X323309Y55921D01*
X321902Y57328D01*
X321672Y57423D01*
Y58798D01*
X322402Y59100D01*
X323809Y60507D01*
X324570Y62344D01*
Y64333D01*
X323809Y66171D01*
X322402Y67578D01*
X321516Y67945D01*
Y69320D01*
X322582Y69761D01*
X323989Y71168D01*
X324750Y73005D01*
Y74995D01*
X323989Y76832D01*
X322582Y78239D01*
X322352Y78334D01*
Y79709D01*
X323082Y80011D01*
X324489Y81418D01*
X325250Y83255D01*
Y85245D01*
X324489Y87082D01*
X323082Y88489D01*
X321603Y89101D01*
X321476Y90420D01*
X321477Y90424D01*
X321902Y90600D01*
X323309Y92007D01*
X324070Y93844D01*
Y95833D01*
X323309Y97671D01*
X321902Y99078D01*
X321672Y99173D01*
Y100548D01*
X322402Y100850D01*
X323809Y102256D01*
X324570Y104094D01*
Y106083D01*
X323809Y107921D01*
X322402Y109328D01*
X321516Y109695D01*
Y111069D01*
X322582Y111511D01*
X323989Y112918D01*
X324750Y114755D01*
Y116745D01*
X323989Y118582D01*
X322582Y119989D01*
X322352Y120084D01*
Y121459D01*
X323082Y121761D01*
X324489Y123168D01*
X325250Y125005D01*
Y126995D01*
X324489Y128832D01*
X323082Y130239D01*
X321245Y131000D01*
D02*
G37*
G36*
X332688Y130554D02*
X330699D01*
X328861Y129793D01*
X327455Y128387D01*
X326693Y126549D01*
Y124560D01*
X327455Y122722D01*
X328861Y121316D01*
X329091Y121220D01*
Y119846D01*
X328361Y119543D01*
X326955Y118137D01*
X326194Y116299D01*
Y114310D01*
X326955Y112472D01*
X328361Y111066D01*
X329248Y110698D01*
Y109324D01*
X328181Y108882D01*
X326775Y107476D01*
X326013Y105638D01*
Y103649D01*
X326775Y101811D01*
X328181Y100404D01*
X328411Y100309D01*
Y98934D01*
X327681Y98632D01*
X326275Y97226D01*
X325513Y95388D01*
Y93399D01*
X326275Y91561D01*
X327681Y90154D01*
X329160Y89542D01*
X329287Y88223D01*
X329287Y88219D01*
X328861Y88043D01*
X327455Y86637D01*
X326693Y84799D01*
Y82810D01*
X327455Y80972D01*
X328861Y79566D01*
X329091Y79470D01*
Y78096D01*
X328361Y77793D01*
X326955Y76387D01*
X326194Y74549D01*
Y72560D01*
X326955Y70722D01*
X328361Y69316D01*
X329248Y68948D01*
Y67574D01*
X328181Y67132D01*
X326775Y65725D01*
X326013Y63888D01*
Y61899D01*
X326775Y60061D01*
X328181Y58654D01*
X328411Y58559D01*
Y57184D01*
X327681Y56882D01*
X326275Y55476D01*
X325513Y53638D01*
Y51649D01*
X326275Y49811D01*
X327681Y48404D01*
X327488Y47110D01*
X327193Y46399D01*
Y44410D01*
X327955Y42572D01*
X329361Y41166D01*
X329591Y41070D01*
Y39696D01*
X328861Y39393D01*
X327455Y37987D01*
X326693Y36149D01*
Y34160D01*
X327455Y32322D01*
X328861Y30916D01*
X330699Y30155D01*
X332688D01*
X334526Y30916D01*
X335932Y32322D01*
X336693Y34160D01*
Y36149D01*
X335932Y37987D01*
X334526Y39393D01*
X334296Y39489D01*
Y40863D01*
X335026Y41166D01*
X336432Y42572D01*
X337193Y44410D01*
Y46399D01*
X336432Y48237D01*
X335026Y49643D01*
X335219Y50938D01*
X335513Y51649D01*
Y53638D01*
X334752Y55476D01*
X333346Y56882D01*
X333116Y56977D01*
Y58352D01*
X333846Y58654D01*
X335252Y60061D01*
X336013Y61899D01*
Y63888D01*
X335252Y65725D01*
X333846Y67132D01*
X332959Y67499D01*
Y68874D01*
X334026Y69316D01*
X335432Y70722D01*
X336194Y72560D01*
Y74549D01*
X335432Y76387D01*
X334026Y77793D01*
X333796Y77888D01*
Y79263D01*
X334526Y79566D01*
X335932Y80972D01*
X336693Y82810D01*
Y84799D01*
X335932Y86637D01*
X334526Y88043D01*
X333047Y88656D01*
X332920Y89974D01*
X332920Y89978D01*
X333346Y90154D01*
X334752Y91561D01*
X335513Y93399D01*
Y95388D01*
X334752Y97226D01*
X333346Y98632D01*
X333116Y98727D01*
Y100102D01*
X333846Y100404D01*
X335252Y101811D01*
X336013Y103649D01*
Y105638D01*
X335252Y107476D01*
X333846Y108882D01*
X332959Y109249D01*
Y110624D01*
X334026Y111066D01*
X335432Y112472D01*
X336194Y114310D01*
Y116299D01*
X335432Y118137D01*
X334026Y119543D01*
X333796Y119639D01*
Y121013D01*
X334526Y121316D01*
X335932Y122722D01*
X336693Y124560D01*
Y126549D01*
X335932Y128387D01*
X334526Y129793D01*
X332688Y130554D01*
D02*
G37*
G36*
X408019Y61500D02*
X403981D01*
X400020Y60712D01*
X396290Y59167D01*
X392932Y56923D01*
X390077Y54068D01*
X387833Y50710D01*
X386288Y46980D01*
X385500Y43019D01*
Y38981D01*
X386288Y35020D01*
X387833Y31290D01*
X390077Y27932D01*
X392932Y25077D01*
X396290Y22833D01*
X400020Y21288D01*
X403981Y20500D01*
X408019D01*
X411980Y21288D01*
X415710Y22833D01*
X419068Y25077D01*
X421923Y27932D01*
X424167Y31290D01*
X425712Y35020D01*
X426500Y38981D01*
Y43019D01*
X425712Y46980D01*
X424167Y50710D01*
X421923Y54068D01*
X419068Y56923D01*
X415710Y59167D01*
X411980Y60712D01*
X408019Y61500D01*
D02*
G37*
%LPD*%
G36*
X256317Y214070D02*
X256106Y213983D01*
X254700Y212576D01*
X253939Y210738D01*
Y208749D01*
X254700Y206912D01*
X256106Y205505D01*
X256317Y205418D01*
Y187031D01*
X256106Y186944D01*
X254700Y185537D01*
X253939Y183700D01*
Y181710D01*
X254700Y179873D01*
X256106Y178466D01*
X256317Y178379D01*
X256317Y57932D01*
Y29420D01*
X243963Y17066D01*
X27661D01*
X16285Y28442D01*
Y217053D01*
X20311Y221689D01*
X20311D01*
X20311Y221689D01*
X20311Y221689D01*
X60830Y221689D01*
X62222Y220008D01*
X62050Y219003D01*
X61380Y218332D01*
X60619Y216495D01*
Y214505D01*
X61380Y212668D01*
X62786Y211261D01*
X64624Y210500D01*
X66613D01*
X68451Y211261D01*
X69858Y212668D01*
X70619Y214505D01*
Y216495D01*
X70064Y217834D01*
X69491Y219761D01*
X70898Y221168D01*
X71113Y221689D01*
X256317Y221689D01*
Y214070D01*
D02*
G37*
%LPC*%
G36*
X244933Y214744D02*
X242944D01*
X241106Y213983D01*
X239700Y212576D01*
X238939Y210738D01*
Y208749D01*
X239700Y206912D01*
X241106Y205505D01*
X242944Y204744D01*
X244933D01*
X246771Y205505D01*
X248178Y206912D01*
X248939Y208749D01*
Y210738D01*
X248178Y212576D01*
X246771Y213983D01*
X244933Y214744D01*
D02*
G37*
G36*
X229418D02*
X227429D01*
X225591Y213983D01*
X224185Y212576D01*
X223424Y210738D01*
Y208749D01*
X224185Y206912D01*
X225591Y205505D01*
X227429Y204744D01*
X229418D01*
X231256Y205505D01*
X232662Y206912D01*
X233424Y208749D01*
Y210738D01*
X232662Y212576D01*
X231256Y213983D01*
X229418Y214744D01*
D02*
G37*
G36*
X66468Y203873D02*
X64479D01*
X62641Y203112D01*
X61234Y201705D01*
X60473Y199867D01*
Y197878D01*
X61234Y196041D01*
X62641Y194634D01*
X64479Y193873D01*
X66468D01*
X68305Y194634D01*
X69712Y196041D01*
X70473Y197878D01*
Y199867D01*
X69712Y201705D01*
X68305Y203112D01*
X66468Y203873D01*
D02*
G37*
G36*
X53113Y202290D02*
X51124D01*
X49286Y201529D01*
X47880Y200123D01*
X47118Y198285D01*
Y196296D01*
X47880Y194458D01*
X49286Y193052D01*
X51124Y192290D01*
X53113D01*
X54951Y193052D01*
X56357Y194458D01*
X57118Y196296D01*
Y198285D01*
X56357Y200123D01*
X54951Y201529D01*
X53113Y202290D01*
D02*
G37*
G36*
X225124Y193721D02*
X223134D01*
X221297Y192960D01*
X219890Y191553D01*
X219129Y189715D01*
Y187726D01*
X219890Y185889D01*
X221297Y184482D01*
X223134Y183721D01*
X225124D01*
X226961Y184482D01*
X228368Y185889D01*
X229129Y187726D01*
Y189715D01*
X228368Y191553D01*
X226961Y192960D01*
X225124Y193721D01*
D02*
G37*
G36*
X61243Y191100D02*
X58057D01*
X54980Y190275D01*
X52220Y188682D01*
X49967Y186430D01*
X48375Y183670D01*
X48350Y183579D01*
X46350Y183842D01*
Y191100D01*
X22150D01*
Y166900D01*
X46350D01*
Y174158D01*
X48350Y174421D01*
X48375Y174330D01*
X49967Y171570D01*
X52220Y169318D01*
X54980Y167725D01*
X58057Y166900D01*
X60973D01*
X61627Y166119D01*
X62141Y165070D01*
X61500Y163522D01*
Y161533D01*
X62261Y159695D01*
X63668Y158288D01*
X65505Y157527D01*
X67495D01*
X69332Y158288D01*
X70739Y159695D01*
X71020Y160373D01*
X73184D01*
X73465Y159695D01*
X74872Y158288D01*
X76710Y157527D01*
X78699D01*
X80536Y158288D01*
X81943Y159695D01*
X82704Y161533D01*
Y163522D01*
X81943Y165360D01*
X80536Y166766D01*
X78699Y167527D01*
X76710D01*
X74872Y166766D01*
X73465Y165360D01*
X73184Y164681D01*
X71020D01*
X70739Y165360D01*
X69332Y166766D01*
X67776Y167411D01*
X67401Y168438D01*
X67289Y169527D01*
X69332Y171570D01*
X70925Y174330D01*
X71750Y177407D01*
Y180593D01*
X70925Y183670D01*
X69332Y186430D01*
X67080Y188682D01*
X64320Y190275D01*
X61243Y191100D01*
D02*
G37*
G36*
X244933Y187955D02*
X242944D01*
X241106Y187194D01*
X239700Y185787D01*
X238939Y183950D01*
Y181961D01*
X239700Y180123D01*
X241106Y178716D01*
X242944Y177955D01*
X244933D01*
X246771Y178716D01*
X248178Y180123D01*
X248939Y181961D01*
Y183950D01*
X248178Y185787D01*
X246771Y187194D01*
X244933Y187955D01*
D02*
G37*
G36*
X131423Y186250D02*
X129434D01*
X127597Y185489D01*
X126190Y184082D01*
X125429Y182245D01*
Y180255D01*
X126190Y178418D01*
X127597Y177011D01*
X129434Y176250D01*
X131423D01*
X133261Y177011D01*
X134668Y178418D01*
X135152Y179588D01*
X137000Y179081D01*
X137000Y177092D01*
X137761Y175254D01*
X139168Y173847D01*
X141005Y173086D01*
X142995D01*
X144832Y173847D01*
X146239Y175254D01*
X147000Y177092D01*
Y179081D01*
X146239Y180918D01*
X144832Y182325D01*
X142995Y183086D01*
X141005D01*
X139168Y182325D01*
X137761Y180918D01*
X137276Y179748D01*
X135429Y180256D01*
X135429Y182245D01*
X134668Y184082D01*
X133261Y185489D01*
X131423Y186250D01*
D02*
G37*
G36*
X160995Y191500D02*
X159005D01*
X157168Y190739D01*
X155761Y189332D01*
X155000Y187495D01*
Y185505D01*
X155761Y183668D01*
X155854Y183575D01*
X156918Y182026D01*
X155511Y180620D01*
X154750Y178782D01*
Y176793D01*
X155511Y174955D01*
X156918Y173549D01*
X158755Y172787D01*
X160745D01*
X162582Y173549D01*
X163989Y174955D01*
X164750Y176793D01*
Y178782D01*
X163989Y180620D01*
X163896Y180712D01*
X162832Y182261D01*
X164239Y183668D01*
X165000Y185505D01*
Y187495D01*
X164239Y189332D01*
X162832Y190739D01*
X160995Y191500D01*
D02*
G37*
G36*
X212995Y179955D02*
X211005D01*
X209168Y179194D01*
X207761Y177787D01*
X207000Y175950D01*
Y173960D01*
X207761Y172123D01*
X209168Y170716D01*
X211005Y169955D01*
X212995D01*
X214832Y170716D01*
X216239Y172123D01*
X217000Y173960D01*
Y175950D01*
X216239Y177787D01*
X214832Y179194D01*
X212995Y179955D01*
D02*
G37*
G36*
X185402Y178689D02*
X183413D01*
X181575Y177928D01*
X180168Y176521D01*
X179407Y174684D01*
Y172695D01*
X180168Y170857D01*
X181575Y169450D01*
X183413Y168689D01*
X185402D01*
X187239Y169450D01*
X188646Y170857D01*
X189407Y172695D01*
Y174684D01*
X188646Y176521D01*
X187239Y177928D01*
X185402Y178689D01*
D02*
G37*
G36*
X172395Y178000D02*
X170406D01*
X168568Y177239D01*
X167161Y175832D01*
X166400Y173995D01*
Y172005D01*
X167161Y170168D01*
X168568Y168761D01*
X170406Y168000D01*
X172395D01*
X174232Y168761D01*
X175639Y170168D01*
X176400Y172005D01*
Y173995D01*
X175639Y175832D01*
X174232Y177239D01*
X172395Y178000D01*
D02*
G37*
G36*
X116245Y167527D02*
X114255D01*
X112418Y166766D01*
X111011Y165360D01*
X110250Y163522D01*
Y161533D01*
X111011Y159695D01*
X112418Y158288D01*
X114255Y157527D01*
X116245D01*
X118082Y158288D01*
X119489Y159695D01*
X120250Y161533D01*
Y163522D01*
X119489Y165360D01*
X118082Y166766D01*
X116245Y167527D01*
D02*
G37*
G36*
X103722D02*
X101733D01*
X99895Y166766D01*
X98489Y165360D01*
X97727Y163522D01*
Y161533D01*
X98489Y159695D01*
X99895Y158288D01*
X101733Y157527D01*
X103722D01*
X105560Y158288D01*
X106966Y159695D01*
X107727Y161533D01*
Y163522D01*
X106966Y165360D01*
X105560Y166766D01*
X103722Y167527D01*
D02*
G37*
G36*
X172995Y152750D02*
X171005D01*
X169168Y151989D01*
X167761Y150582D01*
X167000Y148745D01*
Y146755D01*
X167761Y144918D01*
X169168Y143511D01*
X171005Y142750D01*
X172995D01*
X174832Y143511D01*
X176239Y144918D01*
X177000Y146755D01*
Y148745D01*
X176239Y150582D01*
X174832Y151989D01*
X172995Y152750D01*
D02*
G37*
G36*
X159745Y137850D02*
X157755D01*
X155918Y137089D01*
X154511Y135682D01*
X153750Y133844D01*
Y131855D01*
X154511Y130018D01*
X155918Y128611D01*
X157755Y127850D01*
X159745D01*
X161582Y128611D01*
X162989Y130018D01*
X163750Y131855D01*
Y133844D01*
X162989Y135682D01*
X161582Y137089D01*
X159745Y137850D01*
D02*
G37*
G36*
X92000Y124250D02*
X90011D01*
X88173Y123489D01*
X86767Y122082D01*
X86005Y120245D01*
Y118255D01*
X86767Y116418D01*
X88173Y115011D01*
X88300Y114958D01*
Y112794D01*
X88168Y112739D01*
X86761Y111332D01*
X86000Y109495D01*
Y107505D01*
X86761Y105668D01*
X88168Y104261D01*
X90005Y103500D01*
X91995D01*
X93832Y104261D01*
X95239Y105668D01*
X96000Y107505D01*
Y109495D01*
X95239Y111332D01*
X93832Y112739D01*
X93705Y112792D01*
Y114956D01*
X93838Y115011D01*
X95244Y116418D01*
X96005Y118255D01*
Y120245D01*
X95244Y122082D01*
X93838Y123489D01*
X92000Y124250D01*
D02*
G37*
G36*
X56084Y111500D02*
X54095D01*
X52257Y110739D01*
X50851Y109332D01*
X50090Y107495D01*
Y105505D01*
X50851Y103668D01*
X52257Y102261D01*
X54095Y101500D01*
X56084D01*
X57922Y102261D01*
X59328Y103668D01*
X60090Y105505D01*
Y107495D01*
X59328Y109332D01*
X57922Y110739D01*
X56084Y111500D01*
D02*
G37*
G36*
X115245Y109000D02*
X113255D01*
X111418Y108239D01*
X110011Y106832D01*
X109250Y104995D01*
Y103005D01*
X110011Y101168D01*
X111418Y99761D01*
X113255Y99000D01*
X115245D01*
X117082Y99761D01*
X118489Y101168D01*
X119250Y103005D01*
Y104995D01*
X118489Y106832D01*
X117082Y108239D01*
X115245Y109000D01*
D02*
G37*
G36*
X73031Y107261D02*
X71041D01*
X69204Y106500D01*
X67797Y105093D01*
X67036Y103256D01*
Y101267D01*
X67797Y99429D01*
X69204Y98022D01*
X71041Y97261D01*
X73031D01*
X74868Y98022D01*
X76275Y99429D01*
X77036Y101267D01*
Y103256D01*
X76275Y105093D01*
X74868Y106500D01*
X73031Y107261D01*
D02*
G37*
G36*
X184133Y107103D02*
X182144D01*
X180306Y106342D01*
X178900Y104935D01*
X178138Y103098D01*
Y101109D01*
X178900Y99271D01*
X180306Y97864D01*
X182144Y97103D01*
X184133D01*
X185971Y97864D01*
X187377Y99271D01*
X188138Y101109D01*
Y103098D01*
X187377Y104935D01*
X185971Y106342D01*
X184133Y107103D01*
D02*
G37*
G36*
X173493Y118250D02*
X171503D01*
X169666Y117489D01*
X168259Y116082D01*
X167498Y114245D01*
Y112255D01*
X168259Y110418D01*
X169574Y109103D01*
X169543Y108634D01*
X169046Y107103D01*
X168166D01*
X166328Y106342D01*
X164922Y104935D01*
X164161Y103098D01*
Y101109D01*
X164922Y99271D01*
X166328Y97864D01*
X168166Y97103D01*
X170155D01*
X171993Y97864D01*
X173400Y99271D01*
X174161Y101109D01*
Y103098D01*
X173400Y104935D01*
X172085Y106250D01*
X172115Y106719D01*
X172613Y108250D01*
X173493D01*
X175330Y109011D01*
X176737Y110418D01*
X177498Y112255D01*
Y114245D01*
X176737Y116082D01*
X175330Y117489D01*
X173493Y118250D01*
D02*
G37*
G36*
X130495Y111500D02*
X128505D01*
X126668Y110739D01*
X125261Y109332D01*
X124500Y107495D01*
Y105505D01*
X125261Y103668D01*
X126668Y102261D01*
X127076Y102092D01*
Y99927D01*
X126778Y99804D01*
X125371Y98397D01*
X124610Y96560D01*
Y94571D01*
X125371Y92733D01*
X126778Y91326D01*
X128615Y90565D01*
X130605D01*
X132442Y91326D01*
X133849Y92733D01*
X134610Y94571D01*
Y96560D01*
X133849Y98397D01*
X132442Y99804D01*
X132034Y99973D01*
Y102138D01*
X132332Y102261D01*
X133739Y103668D01*
X134500Y105505D01*
Y107495D01*
X133739Y109332D01*
X132332Y110739D01*
X130495Y111500D01*
D02*
G37*
G36*
X56084Y98504D02*
X54095D01*
X52257Y97743D01*
X50851Y96336D01*
X50090Y94499D01*
Y92509D01*
X50851Y90672D01*
X52257Y89265D01*
X54095Y88504D01*
X56084D01*
X57922Y89265D01*
X59328Y90672D01*
X60090Y92509D01*
Y94499D01*
X59328Y96336D01*
X57922Y97743D01*
X56084Y98504D01*
D02*
G37*
G36*
X42910D02*
X40921D01*
X39083Y97743D01*
X37677Y96336D01*
X36916Y94499D01*
Y92509D01*
X37677Y90672D01*
X39083Y89265D01*
X40921Y88504D01*
X42910D01*
X44748Y89265D01*
X46154Y90672D01*
X46916Y92509D01*
Y94499D01*
X46154Y96336D01*
X44748Y97743D01*
X42910Y98504D01*
D02*
G37*
G36*
X28073D02*
X26083D01*
X24246Y97743D01*
X22839Y96336D01*
X22078Y94499D01*
Y92509D01*
X22839Y90672D01*
X24246Y89265D01*
X26083Y88504D01*
X28073D01*
X29910Y89265D01*
X31317Y90672D01*
X32078Y92509D01*
Y94499D01*
X31317Y96336D01*
X29910Y97743D01*
X28073Y98504D01*
D02*
G37*
G36*
X54000Y63644D02*
Y54000D01*
X63644D01*
X63105Y56014D01*
X61395Y58976D01*
X58976Y61395D01*
X56014Y63105D01*
X54000Y63644D01*
D02*
G37*
G36*
X48000Y63644D02*
X45986Y63105D01*
X43024Y61395D01*
X40605Y58976D01*
X38895Y56014D01*
X38356Y54000D01*
X48000D01*
Y63644D01*
D02*
G37*
G36*
X97019Y91500D02*
X92981D01*
X89020Y90712D01*
X85289Y89167D01*
X81932Y86923D01*
X79077Y84068D01*
X76833Y80710D01*
X75288Y76980D01*
X74500Y73019D01*
Y68981D01*
X75288Y65020D01*
X76833Y61290D01*
X79077Y57932D01*
X81932Y55077D01*
X85289Y52833D01*
X89020Y51288D01*
X92981Y50500D01*
X97019D01*
X100980Y51288D01*
X104710Y52833D01*
X108068Y55077D01*
X110923Y57932D01*
X113167Y61290D01*
X114712Y65020D01*
X115500Y68981D01*
Y73019D01*
X114712Y76980D01*
X113167Y80710D01*
X110923Y84068D01*
X108068Y86923D01*
X104710Y89167D01*
X100980Y90712D01*
X97019Y91500D01*
D02*
G37*
G36*
X48000Y48000D02*
X38356D01*
X38895Y45986D01*
X40605Y43024D01*
X43024Y40605D01*
X45986Y38895D01*
X48000Y38356D01*
Y48000D01*
D02*
G37*
G36*
X63644D02*
X54000D01*
Y38356D01*
X56014Y38895D01*
X58976Y40605D01*
X61395Y43024D01*
X63105Y45986D01*
X63644Y48000D01*
D02*
G37*
%LPD*%
D76*
X34250Y179000D02*
D03*
D77*
X59650D02*
D03*
D78*
X192000Y484000D02*
D03*
X51000Y457000D02*
D03*
X457000Y51000D02*
D03*
Y457000D02*
D03*
X132000Y484000D02*
D03*
X102000D02*
D03*
X72000D02*
D03*
X457000Y254000D02*
D03*
X51000Y51000D02*
D03*
X162000Y484000D02*
D03*
D79*
X465000Y138000D02*
D03*
Y349000D02*
D03*
D80*
X315000Y203311D02*
D03*
X241500Y478750D02*
D03*
X220968Y339000D02*
D03*
X349911Y39320D02*
D03*
X350161Y52070D02*
D03*
X350607Y63513D02*
D03*
X350161Y75070D02*
D03*
X360411Y74570D02*
D03*
X360857Y63014D02*
D03*
X360411Y51570D02*
D03*
X360161Y38820D02*
D03*
X350911Y90320D02*
D03*
X351161Y103070D02*
D03*
X351607Y114514D02*
D03*
X351161Y126070D02*
D03*
X361411Y125570D02*
D03*
X361857Y114014D02*
D03*
X361411Y102570D02*
D03*
X361161Y89820D02*
D03*
X308000Y46100D02*
D03*
X320750Y45850D02*
D03*
X332193Y45405D02*
D03*
X343750Y45850D02*
D03*
X343250Y35600D02*
D03*
X331693Y35155D02*
D03*
X320250Y35600D02*
D03*
X307500Y35850D02*
D03*
Y84500D02*
D03*
X320250Y84250D02*
D03*
X331693Y83804D02*
D03*
X343250Y84250D02*
D03*
X342750Y74000D02*
D03*
X331194Y73554D02*
D03*
X319750Y74000D02*
D03*
X307000Y74250D02*
D03*
X306320Y53339D02*
D03*
X319070Y53089D02*
D03*
X330513Y52643D02*
D03*
X342070Y53089D02*
D03*
X342570Y63339D02*
D03*
X331013Y62893D02*
D03*
X319570Y63339D02*
D03*
X306820Y63589D02*
D03*
Y105339D02*
D03*
X319570Y105089D02*
D03*
X331013Y104643D02*
D03*
X342570Y105089D02*
D03*
X342070Y94839D02*
D03*
X330513Y94393D02*
D03*
X319070Y94839D02*
D03*
X306320Y95089D02*
D03*
X307000Y116000D02*
D03*
X319750Y115750D02*
D03*
X331194Y115304D02*
D03*
X342750Y115750D02*
D03*
X343250Y126000D02*
D03*
X331693Y125554D02*
D03*
X320250Y126000D02*
D03*
X307500Y126250D02*
D03*
X192905Y69250D02*
D03*
X183138Y69052D02*
D03*
X173250Y65020D02*
D03*
X161750Y64750D02*
D03*
X149500Y63250D02*
D03*
X234398Y422690D02*
D03*
X223373Y415288D02*
D03*
X298715Y489190D02*
D03*
X351500Y488750D02*
D03*
X445113Y472750D02*
D03*
X475000Y447750D02*
D03*
X331500Y400274D02*
D03*
X327000Y392924D02*
D03*
X342703Y406495D02*
D03*
X206542Y332843D02*
D03*
X193292Y330805D02*
D03*
X145000Y264000D02*
D03*
X156752Y276869D02*
D03*
X83952Y262552D02*
D03*
X17462Y347587D02*
D03*
X363500Y449682D02*
D03*
X241197Y308750D02*
D03*
X285250Y446030D02*
D03*
X372500Y440000D02*
D03*
X440352Y374949D02*
D03*
X294500Y454750D02*
D03*
X270921Y437500D02*
D03*
X267761Y319250D02*
D03*
X172000Y147750D02*
D03*
X158750Y132850D02*
D03*
X52118Y197290D02*
D03*
X65473Y198873D02*
D03*
X65619Y215500D02*
D03*
X66659Y224000D02*
D03*
X87000Y475250D02*
D03*
X117080Y493963D02*
D03*
X177000Y492750D02*
D03*
X209500Y489750D02*
D03*
X444999Y421418D02*
D03*
X69000Y463250D02*
D03*
X289250Y269500D02*
D03*
X343677Y360775D02*
D03*
X391028Y361264D02*
D03*
X354750Y339500D02*
D03*
X363284Y389088D02*
D03*
X259492Y353693D02*
D03*
X274414Y352344D02*
D03*
X334750Y326000D02*
D03*
X297250Y385500D02*
D03*
X228424Y209744D02*
D03*
X224129Y188721D02*
D03*
X243500Y244381D02*
D03*
X212000Y174955D02*
D03*
X159750Y177787D02*
D03*
X171400Y173000D02*
D03*
X258939Y182705D02*
D03*
X243939Y182955D02*
D03*
X270189Y187644D02*
D03*
X258939Y209744D02*
D03*
X243939D02*
D03*
X279206Y190705D02*
D03*
X315250Y392363D02*
D03*
X345269Y393919D02*
D03*
X169161Y102103D02*
D03*
X183138D02*
D03*
X172498Y113250D02*
D03*
X95610Y353378D02*
D03*
X184407Y173689D02*
D03*
X146750Y230310D02*
D03*
X350250Y211521D02*
D03*
X344750Y243000D02*
D03*
X332000D02*
D03*
X243500Y257561D02*
D03*
X293674Y244381D02*
D03*
X206956Y397805D02*
D03*
X207706Y432800D02*
D03*
X175750D02*
D03*
X51500Y390689D02*
D03*
X103750Y358378D02*
D03*
X142000Y359750D02*
D03*
X109250Y377668D02*
D03*
X139750Y463508D02*
D03*
X17785Y397960D02*
D03*
X17500Y388019D02*
D03*
Y377710D02*
D03*
Y367710D02*
D03*
Y357460D02*
D03*
X8744Y354901D02*
D03*
X244245Y292311D02*
D03*
X393250Y242500D02*
D03*
X272892Y294750D02*
D03*
X55967Y354628D02*
D03*
X27078Y93504D02*
D03*
X129610Y95565D02*
D03*
X55090Y93504D02*
D03*
X91000Y108500D02*
D03*
X391579Y185091D02*
D03*
X403000Y173750D02*
D03*
Y263500D02*
D03*
X414482Y274431D02*
D03*
X273500Y244381D02*
D03*
X258000D02*
D03*
Y292250D02*
D03*
X363962Y297432D02*
D03*
X232250Y291385D02*
D03*
X264500Y375775D02*
D03*
X375750Y322588D02*
D03*
X145319Y249000D02*
D03*
X160000Y186500D02*
D03*
X84365Y251500D02*
D03*
X22702Y246500D02*
D03*
X52108Y254060D02*
D03*
X102727Y162527D02*
D03*
X66500D02*
D03*
X77704D02*
D03*
X115250D02*
D03*
X142000Y178086D02*
D03*
X130429Y181250D02*
D03*
X114250Y104000D02*
D03*
X72036Y102261D02*
D03*
X41916Y93504D02*
D03*
X55090Y106500D02*
D03*
X91005Y119250D02*
D03*
X129500Y106500D02*
D03*
X403000Y185091D02*
D03*
X403000Y274431D02*
D03*
M02*
